(kicad_pcb
	(version 20260206)
	(generator "pcbnew")
	(generator_version "10.0")
	(general
		(thickness 1.6)
		(legacy_teardrops no)
	)
	(paper "A4")
	(title_block
		(title "04192023_DAF0TMB3IC0_F0TG_MB_C_brd_V02_OCP.brd")
		(comment 1 "Grand Teton / footprints 2817-2823 of 8354")
	)
	(layers
		(0 "F.Cu" signal "TOP")
		(4 "In1.Cu" signal "GND")
		(6 "In2.Cu" signal "IN1")
		(8 "In3.Cu" signal "GND1")
		(10 "In4.Cu" signal "IN2")
		(12 "In5.Cu" signal "GND2")
		(14 "In6.Cu" signal "IN3")
		(16 "In7.Cu" signal "GND3")
		(18 "In8.Cu" signal "VCC")
		(20 "In9.Cu" signal "VCC1")
		(22 "In10.Cu" signal "GND4")
		(24 "In11.Cu" signal "IN4")
		(26 "In12.Cu" signal "GND5")
		(28 "In13.Cu" signal "IN5")
		(30 "In14.Cu" signal "GND6")
		(32 "In15.Cu" signal "IN6")
		(34 "In16.Cu" signal "GND7")
		(2 "B.Cu" signal "BOTTOM")
		(9 "F.Adhes" user "F.Adhesive")
		(11 "B.Adhes" user "B.Adhesive")
		(13 "F.Paste" user "Package Geometry/Pastemask Top")
		(15 "B.Paste" user "Package Geometry/Pastemask Bottom")
		(5 "F.SilkS" user "Ref Des/Silkscreen Top")
		(7 "B.SilkS" user "Ref Des/Silkscreen Bottom")
		(1 "F.Mask" user "Board Geometry/Soldermask Top")
		(3 "B.Mask" user "Board Geometry/Soldermask Bottom")
		(17 "Dwgs.User" user "User.Drawings")
		(19 "Cmts.User" user "User.Comments")
		(21 "Eco1.User" user "User.Eco1")
		(23 "Eco2.User" user "User.Eco2")
		(25 "Edge.Cuts" user "Board Geometry/Outline")
		(27 "Margin" user)
		(31 "F.CrtYd" user "Package Geometry/Place Bound Top")
		(29 "B.CrtYd" user "Package Geometry/Place Bound Bottom")
		(35 "F.Fab" user "Ref Des/Assembly Top")
		(33 "B.Fab" user "Ref Des/Assembly Bottom")
	)
	(footprint ""
		(layer "F.Cu")
		(at 38.0746 -435.448964 -90)
		(property "Reference" "R2918"
			(at 0 0 270)
			(layer "F.SilkS")
			(hide yes)
			(effects
				(font
					(size 1.27 1.27)
				)
			)
		)
		(property "Value" ""
			(at 0 0 270)
			(layer "F.Fab")
			(effects
				(font
					(size 1.27 1.27)
				)
			)
		)
		(duplicate_pad_numbers_are_jumpers no)
		(fp_line
			(start -0.7874 0.4064)
			(end -0.7874 -0.4064)
			(stroke
				(width 0.1524)
				(type default)
			)
			(layer "F.SilkS")
		)
		(fp_line
			(start 0.7874 0.4064)
			(end -0.7874 0.4064)
			(stroke
				(width 0.1524)
				(type default)
			)
			(layer "F.SilkS")
		)
		(fp_line
			(start -0.7874 -0.4064)
			(end 0.7874 -0.4064)
			(stroke
				(width 0.1524)
				(type default)
			)
			(layer "F.SilkS")
		)
		(fp_line
			(start 0.7874 -0.4064)
			(end 0.7874 0.4064)
			(stroke
				(width 0.1524)
				(type default)
			)
			(layer "F.SilkS")
		)
		(fp_line
			(start -0.67945 0.3048)
			(end -0.67945 -0.305054)
			(stroke
				(width 0.1)
				(type default)
			)
			(layer "F.Fab")
		)
		(fp_line
			(start -0.12065 0.3048)
			(end -0.67945 0.3048)
			(stroke
				(width 0.1)
				(type default)
			)
			(layer "F.Fab")
		)
		(fp_line
			(start 0.120396 0.3048)
			(end 0.120396 0.2794)
			(stroke
				(width 0.1)
				(type default)
			)
			(layer "F.Fab")
		)
		(fp_line
			(start 0.67945 0.3048)
			(end 0.120396 0.3048)
			(stroke
				(width 0.1)
				(type default)
			)
			(layer "F.Fab")
		)
		(fp_line
			(start -0.12065 0.2794)
			(end -0.12065 0.3048)
			(stroke
				(width 0.1)
				(type default)
			)
			(layer "F.Fab")
		)
		(fp_line
			(start 0.120396 0.2794)
			(end -0.12065 0.2794)
			(stroke
				(width 0.1)
				(type default)
			)
			(layer "F.Fab")
		)
		(fp_line
			(start -0.12065 -0.2794)
			(end 0.12065 -0.2794)
			(stroke
				(width 0.1)
				(type default)
			)
			(layer "F.Fab")
		)
		(fp_line
			(start 0.12065 -0.2794)
			(end 0.12065 -0.3048)
			(stroke
				(width 0.1)
				(type default)
			)
			(layer "F.Fab")
		)
		(fp_line
			(start 0.12065 -0.3048)
			(end 0.67945 -0.3048)
			(stroke
				(width 0.1)
				(type default)
			)
			(layer "F.Fab")
		)
		(fp_line
			(start 0.67945 -0.3048)
			(end 0.67945 0.3048)
			(stroke
				(width 0.1)
				(type default)
			)
			(layer "F.Fab")
		)
		(fp_line
			(start -0.67945 -0.305054)
			(end -0.12065 -0.305054)
			(stroke
				(width 0.1)
				(type default)
			)
			(layer "F.Fab")
		)
		(fp_line
			(start -0.12065 -0.305054)
			(end -0.12065 -0.2794)
			(stroke
				(width 0.1)
				(type default)
			)
			(layer "F.Fab")
		)
		(pad "1" smd circle
			(at -0.40005 0 270)
			(size 0 0)
			(layers "F.Cu" "F.Mask" "F.Paste")
			(net "FM_SWB_PWR_EN_R")
		)
		(pad "2" smd circle
			(at 0.40005 0 270)
			(size 0 0)
			(layers "F.Cu" "F.Mask" "F.Paste")
			(net "GND")
		)
	)
	(footprint ""
		(layer "F.Cu")
		(at 427.834552 -355.524562)
		(property "Reference" "PC207_1"
			(at 0 0 0)
			(layer "F.SilkS")
			(hide yes)
			(effects
				(font
					(size 1.27 1.27)
				)
			)
		)
		(property "Value" ""
			(at 0 0 0)
			(layer "F.Fab")
			(effects
				(font
					(size 1.27 1.27)
				)
			)
		)
		(duplicate_pad_numbers_are_jumpers no)
		(fp_line
			(start -0.7874 -0.4064)
			(end 0.7874 -0.4064)
			(stroke
				(width 0.1524)
				(type default)
			)
			(layer "F.SilkS")
		)
		(fp_line
			(start -0.7874 0.4064)
			(end -0.7874 -0.4064)
			(stroke
				(width 0.1524)
				(type default)
			)
			(layer "F.SilkS")
		)
		(fp_line
			(start 0.7874 -0.4064)
			(end 0.7874 0.4064)
			(stroke
				(width 0.1524)
				(type default)
			)
			(layer "F.SilkS")
		)
		(fp_line
			(start 0.7874 0.4064)
			(end -0.7874 0.4064)
			(stroke
				(width 0.1524)
				(type default)
			)
			(layer "F.SilkS")
		)
		(fp_line
			(start -0.67945 -0.305054)
			(end -0.12065 -0.305054)
			(stroke
				(width 0.1)
				(type default)
			)
			(layer "F.Fab")
		)
		(fp_line
			(start -0.67945 0.3048)
			(end -0.67945 -0.305054)
			(stroke
				(width 0.1)
				(type default)
			)
			(layer "F.Fab")
		)
		(fp_line
			(start -0.12065 -0.305054)
			(end -0.12065 -0.2794)
			(stroke
				(width 0.1)
				(type default)
			)
			(layer "F.Fab")
		)
		(fp_line
			(start -0.12065 -0.2794)
			(end 0.12065 -0.2794)
			(stroke
				(width 0.1)
				(type default)
			)
			(layer "F.Fab")
		)
		(fp_line
			(start -0.12065 0.2794)
			(end -0.12065 0.3048)
			(stroke
				(width 0.1)
				(type default)
			)
			(layer "F.Fab")
		)
		(fp_line
			(start -0.12065 0.3048)
			(end -0.67945 0.3048)
			(stroke
				(width 0.1)
				(type default)
			)
			(layer "F.Fab")
		)
		(fp_line
			(start 0.120396 0.2794)
			(end -0.12065 0.2794)
			(stroke
				(width 0.1)
				(type default)
			)
			(layer "F.Fab")
		)
		(fp_line
			(start 0.120396 0.3048)
			(end 0.120396 0.2794)
			(stroke
				(width 0.1)
				(type default)
			)
			(layer "F.Fab")
		)
		(fp_line
			(start 0.12065 -0.3048)
			(end 0.67945 -0.3048)
			(stroke
				(width 0.1)
				(type default)
			)
			(layer "F.Fab")
		)
		(fp_line
			(start 0.12065 -0.2794)
			(end 0.12065 -0.3048)
			(stroke
				(width 0.1)
				(type default)
			)
			(layer "F.Fab")
		)
		(fp_line
			(start 0.67945 -0.3048)
			(end 0.67945 0.3048)
			(stroke
				(width 0.1)
				(type default)
			)
			(layer "F.Fab")
		)
		(fp_line
			(start 0.67945 0.3048)
			(end 0.120396 0.3048)
			(stroke
				(width 0.1)
				(type default)
			)
			(layer "F.Fab")
		)
		(pad "1" smd circle
			(at -0.40005 0)
			(size 0 0)
			(layers "F.Cu" "F.Mask" "F.Paste")
			(net "SW_P12V_AUX_PVDD11_S3_P0_FLT")
		)
		(pad "2" smd circle
			(at 0.40005 0)
			(size 0 0)
			(layers "F.Cu" "F.Mask" "F.Paste")
			(net "GND")
		)
	)
	(footprint ""
		(layer "F.Cu")
		(at 132.885942 -146.856196)
		(property "Reference" "H8027"
			(at -6.168898 4.4323 0)
			(unlocked yes)
			(layer "F.SilkS")
			(effects
				(font
					(size 0.7874 0.5842)
					(thickness 0.1524)
				)
				(justify left)
			)
		)
		(property "Value" ""
			(at 0 0 0)
			(layer "F.Fab")
			(effects
				(font
					(size 1.27 1.27)
				)
			)
		)
		(duplicate_pad_numbers_are_jumpers no)
		(pad "1" thru_hole circle
			(at 0 0)
			(size 6.1976 6.1976)
			(drill 3.7338)
			(layers "*.Cu" "*.Mask")
			(remove_unused_layers no)
			(net "GND")
			(clearance -0.9779)
			(padstack
				(mode front_inner_back)
				(layer "Inner"
					(shape circle)
					(size 5.5372 5.5372)
					(clearance -0.6477)
				)
				(layer "B.Cu"
					(shape circle)
					(size 6.1976 6.1976)
					(clearance -0.9779)
				)
			)
		)
	)
	(footprint ""
		(layer "F.Cu")
		(at 271.607788 -102.247192 90)
		(property "Reference" "C1509"
			(at 0 0 90)
			(layer "F.SilkS")
			(hide yes)
			(effects
				(font
					(size 1.27 1.27)
				)
			)
		)
		(property "Value" ""
			(at 0 0 90)
			(layer "F.Fab")
			(effects
				(font
					(size 1.27 1.27)
				)
			)
		)
		(duplicate_pad_numbers_are_jumpers no)
		(fp_line
			(start 0.7874 -0.4064)
			(end 0.7874 0.4064)
			(stroke
				(width 0.1524)
				(type default)
			)
			(layer "F.SilkS")
		)
		(fp_line
			(start -0.7874 -0.4064)
			(end 0.7874 -0.4064)
			(stroke
				(width 0.1524)
				(type default)
			)
			(layer "F.SilkS")
		)
		(fp_line
			(start 0.7874 0.4064)
			(end -0.7874 0.4064)
			(stroke
				(width 0.1524)
				(type default)
			)
			(layer "F.SilkS")
		)
		(fp_line
			(start -0.7874 0.4064)
			(end -0.7874 -0.4064)
			(stroke
				(width 0.1524)
				(type default)
			)
			(layer "F.SilkS")
		)
		(fp_line
			(start -0.12065 -0.305054)
			(end -0.12065 -0.2794)
			(stroke
				(width 0.1)
				(type default)
			)
			(layer "F.Fab")
		)
		(fp_line
			(start -0.67945 -0.305054)
			(end -0.12065 -0.305054)
			(stroke
				(width 0.1)
				(type default)
			)
			(layer "F.Fab")
		)
		(fp_line
			(start 0.67945 -0.3048)
			(end 0.67945 0.3048)
			(stroke
				(width 0.1)
				(type default)
			)
			(layer "F.Fab")
		)
		(fp_line
			(start 0.12065 -0.3048)
			(end 0.67945 -0.3048)
			(stroke
				(width 0.1)
				(type default)
			)
			(layer "F.Fab")
		)
		(fp_line
			(start 0.12065 -0.2794)
			(end 0.12065 -0.3048)
			(stroke
				(width 0.1)
				(type default)
			)
			(layer "F.Fab")
		)
		(fp_line
			(start -0.12065 -0.2794)
			(end 0.12065 -0.2794)
			(stroke
				(width 0.1)
				(type default)
			)
			(layer "F.Fab")
		)
		(fp_line
			(start 0.120396 0.2794)
			(end -0.12065 0.2794)
			(stroke
				(width 0.1)
				(type default)
			)
			(layer "F.Fab")
		)
		(fp_line
			(start -0.12065 0.2794)
			(end -0.12065 0.3048)
			(stroke
				(width 0.1)
				(type default)
			)
			(layer "F.Fab")
		)
		(fp_line
			(start 0.67945 0.3048)
			(end 0.120396 0.3048)
			(stroke
				(width 0.1)
				(type default)
			)
			(layer "F.Fab")
		)
		(fp_line
			(start 0.120396 0.3048)
			(end 0.120396 0.2794)
			(stroke
				(width 0.1)
				(type default)
			)
			(layer "F.Fab")
		)
		(fp_line
			(start -0.12065 0.3048)
			(end -0.67945 0.3048)
			(stroke
				(width 0.1)
				(type default)
			)
			(layer "F.Fab")
		)
		(fp_line
			(start -0.67945 0.3048)
			(end -0.67945 -0.305054)
			(stroke
				(width 0.1)
				(type default)
			)
			(layer "F.Fab")
		)
		(pad "1" smd circle
			(at -0.40005 0 90)
			(size 0 0)
			(layers "F.Cu" "F.Mask" "F.Paste")
			(net "PVDD18_S5_P0")
		)
		(pad "2" smd circle
			(at 0.40005 0 90)
			(size 0 0)
			(layers "F.Cu" "F.Mask" "F.Paste")
			(net "GND")
		)
	)
	(footprint ""
		(layer "F.Cu")
		(at 361.316016 -256.012188 90)
		(property "Reference" "C2148"
			(at 0 0 90)
			(layer "F.SilkS")
			(hide yes)
			(effects
				(font
					(size 1.27 1.27)
				)
			)
		)
		(property "Value" ""
			(at 0 0 90)
			(layer "F.Fab")
			(effects
				(font
					(size 1.27 1.27)
				)
			)
		)
		(duplicate_pad_numbers_are_jumpers no)
		(fp_line
			(start 0.7874 -0.4064)
			(end 0.7874 0.4064)
			(stroke
				(width 0.1524)
				(type default)
			)
			(layer "F.SilkS")
		)
		(fp_line
			(start -0.7874 -0.4064)
			(end 0.7874 -0.4064)
			(stroke
				(width 0.1524)
				(type default)
			)
			(layer "F.SilkS")
		)
		(fp_line
			(start 0.7874 0.4064)
			(end -0.7874 0.4064)
			(stroke
				(width 0.1524)
				(type default)
			)
			(layer "F.SilkS")
		)
		(fp_line
			(start -0.7874 0.4064)
			(end -0.7874 -0.4064)
			(stroke
				(width 0.1524)
				(type default)
			)
			(layer "F.SilkS")
		)
		(fp_line
			(start -0.12065 -0.305054)
			(end -0.12065 -0.2794)
			(stroke
				(width 0.1)
				(type default)
			)
			(layer "F.Fab")
		)
		(fp_line
			(start -0.67945 -0.305054)
			(end -0.12065 -0.305054)
			(stroke
				(width 0.1)
				(type default)
			)
			(layer "F.Fab")
		)
		(fp_line
			(start 0.67945 -0.3048)
			(end 0.67945 0.3048)
			(stroke
				(width 0.1)
				(type default)
			)
			(layer "F.Fab")
		)
		(fp_line
			(start 0.12065 -0.3048)
			(end 0.67945 -0.3048)
			(stroke
				(width 0.1)
				(type default)
			)
			(layer "F.Fab")
		)
		(fp_line
			(start 0.12065 -0.2794)
			(end 0.12065 -0.3048)
			(stroke
				(width 0.1)
				(type default)
			)
			(layer "F.Fab")
		)
		(fp_line
			(start -0.12065 -0.2794)
			(end 0.12065 -0.2794)
			(stroke
				(width 0.1)
				(type default)
			)
			(layer "F.Fab")
		)
		(fp_line
			(start 0.120396 0.2794)
			(end -0.12065 0.2794)
			(stroke
				(width 0.1)
				(type default)
			)
			(layer "F.Fab")
		)
		(fp_line
			(start -0.12065 0.2794)
			(end -0.12065 0.3048)
			(stroke
				(width 0.1)
				(type default)
			)
			(layer "F.Fab")
		)
		(fp_line
			(start 0.67945 0.3048)
			(end 0.120396 0.3048)
			(stroke
				(width 0.1)
				(type default)
			)
			(layer "F.Fab")
		)
		(fp_line
			(start 0.120396 0.3048)
			(end 0.120396 0.2794)
			(stroke
				(width 0.1)
				(type default)
			)
			(layer "F.Fab")
		)
		(fp_line
			(start -0.12065 0.3048)
			(end -0.67945 0.3048)
			(stroke
				(width 0.1)
				(type default)
			)
			(layer "F.Fab")
		)
		(fp_line
			(start -0.67945 0.3048)
			(end -0.67945 -0.305054)
			(stroke
				(width 0.1)
				(type default)
			)
			(layer "F.Fab")
		)
		(pad "1" smd circle
			(at -0.40005 0 90)
			(size 0 0)
			(layers "F.Cu" "F.Mask" "F.Paste")
			(net "PVDDCR_SOC_P0")
		)
		(pad "2" smd circle
			(at 0.40005 0 90)
			(size 0 0)
			(layers "F.Cu" "F.Mask" "F.Paste")
			(net "GND")
		)
	)
	(footprint ""
		(layer "F.Cu")
		(at 169.230548 -429.022002 180)
		(property "Reference" "R6791"
			(at 0 0 180)
			(layer "F.SilkS")
			(hide yes)
			(effects
				(font
					(size 1.27 1.27)
				)
			)
		)
		(property "Value" ""
			(at 0 0 180)
			(layer "F.Fab")
			(effects
				(font
					(size 1.27 1.27)
				)
			)
		)
		(duplicate_pad_numbers_are_jumpers no)
		(fp_line
			(start 0.32512 0.175006)
			(end -0.32512 0.175006)
			(stroke
				(width 0.1)
				(type default)
			)
			(layer "F.Fab")
		)
		(fp_line
			(start 0.32512 -0.175006)
			(end 0.32512 0.175006)
			(stroke
				(width 0.1)
				(type default)
			)
			(layer "F.Fab")
		)
		(fp_line
			(start -0.32512 0.175006)
			(end -0.32512 -0.175006)
			(stroke
				(width 0.1)
				(type default)
			)
			(layer "F.Fab")
		)
		(fp_line
			(start -0.32512 -0.175006)
			(end 0.32512 -0.175006)
			(stroke
				(width 0.1)
				(type default)
			)
			(layer "F.Fab")
		)
		(pad "1" smd rect
			(at -0.2667 0 180)
			(size 0.3048 0.381)
			(layers "F.Cu" "F.Mask" "F.Paste")
			(net "U21_E2")
		)
		(pad "2" smd rect
			(at 0.2667 0)
			(size 0.3048 0.381)
			(layers "F.Cu" "F.Mask" "F.Paste")
			(net "GND")
		)
	)
	(footprint ""
		(layer "F.Cu")
		(at 193.294 -54.356 90)
		(property "Reference" "R8029"
			(at 0 0 90)
			(layer "F.SilkS")
			(hide yes)
			(effects
				(font
					(size 1.27 1.27)
				)
			)
		)
		(property "Value" ""
			(at 0 0 90)
			(layer "F.Fab")
			(effects
				(font
					(size 1.27 1.27)
				)
			)
		)
		(duplicate_pad_numbers_are_jumpers no)
		(fp_line
			(start 0.7874 -0.4064)
			(end 0.7874 0.4064)
			(stroke
				(width 0.1524)
				(type default)
			)
			(layer "F.SilkS")
		)
		(fp_line
			(start -0.7874 -0.4064)
			(end 0.7874 -0.4064)
			(stroke
				(width 0.1524)
				(type default)
			)
			(layer "F.SilkS")
		)
		(fp_line
			(start 0.7874 0.4064)
			(end -0.7874 0.4064)
			(stroke
				(width 0.1524)
				(type default)
			)
			(layer "F.SilkS")
		)
		(fp_line
			(start -0.7874 0.4064)
			(end -0.7874 -0.4064)
			(stroke
				(width 0.1524)
				(type default)
			)
			(layer "F.SilkS")
		)
		(fp_line
			(start -0.12065 -0.305054)
			(end -0.12065 -0.2794)
			(stroke
				(width 0.1)
				(type default)
			)
			(layer "F.Fab")
		)
		(fp_line
			(start -0.67945 -0.305054)
			(end -0.12065 -0.305054)
			(stroke
				(width 0.1)
				(type default)
			)
			(layer "F.Fab")
		)
		(fp_line
			(start 0.67945 -0.3048)
			(end 0.67945 0.3048)
			(stroke
				(width 0.1)
				(type default)
			)
			(layer "F.Fab")
		)
		(fp_line
			(start 0.12065 -0.3048)
			(end 0.67945 -0.3048)
			(stroke
				(width 0.1)
				(type default)
			)
			(layer "F.Fab")
		)
		(fp_line
			(start 0.12065 -0.2794)
			(end 0.12065 -0.3048)
			(stroke
				(width 0.1)
				(type default)
			)
			(layer "F.Fab")
		)
		(fp_line
			(start -0.12065 -0.2794)
			(end 0.12065 -0.2794)
			(stroke
				(width 0.1)
				(type default)
			)
			(layer "F.Fab")
		)
		(fp_line
			(start 0.120396 0.2794)
			(end -0.12065 0.2794)
			(stroke
				(width 0.1)
				(type default)
			)
			(layer "F.Fab")
		)
		(fp_line
			(start -0.12065 0.2794)
			(end -0.12065 0.3048)
			(stroke
				(width 0.1)
				(type default)
			)
			(layer "F.Fab")
		)
		(fp_line
			(start 0.67945 0.3048)
			(end 0.120396 0.3048)
			(stroke
				(width 0.1)
				(type default)
			)
			(layer "F.Fab")
		)
		(fp_line
			(start 0.120396 0.3048)
			(end 0.120396 0.2794)
			(stroke
				(width 0.1)
				(type default)
			)
			(layer "F.Fab")
		)
		(fp_line
			(start -0.12065 0.3048)
			(end -0.67945 0.3048)
			(stroke
				(width 0.1)
				(type default)
			)
			(layer "F.Fab")
		)
		(fp_line
			(start -0.67945 0.3048)
			(end -0.67945 -0.305054)
			(stroke
				(width 0.1)
				(type default)
			)
			(layer "F.Fab")
		)
		(pad "1" smd circle
			(at -0.40005 0 90)
			(size 0 0)
			(layers "F.Cu" "F.Mask" "F.Paste")
			(net "LED_P12V_SCM_FAULT")
		)
		(pad "2" smd circle
			(at 0.40005 0 90)
			(size 0 0)
			(layers "F.Cu" "F.Mask" "F.Paste")
			(net "P3V3_AUX")
		)
	)
)
